(kicad_pcb
	(version 20260206)
	(generator "pcbnew")
	(generator_version "10.0")
	(general
		(thickness 1.6)
		(legacy_teardrops no)
	)
	(paper "A4")
	(title_block
		(title "v1-chassis-manager — T6M_CM_d_v01_1031_1645.brd")
		(comment 1 "Open CloudServer (Microsoft) / footprints 2204-2213 of 2512")
	)
	(layers
		(0 "F.Cu" signal "TOP")
		(4 "In1.Cu" signal "GND1")
		(6 "In2.Cu" signal "IN1")
		(8 "In3.Cu" signal "VCC1")
		(10 "In4.Cu" signal "VCC2")
		(12 "In5.Cu" signal "GND2")
		(14 "In6.Cu" signal "IN2")
		(16 "In7.Cu" signal "IN3")
		(18 "In8.Cu" signal "GND3")
		(2 "B.Cu" signal "BOTTOM")
		(9 "F.Adhes" user "F.Adhesive")
		(11 "B.Adhes" user "B.Adhesive")
		(13 "F.Paste" user "Package Geometry/Pastemask Top")
		(15 "B.Paste" user "Package Geometry/Pastemask Bottom")
		(5 "F.SilkS" user "Ref Des/Silkscreen Top")
		(7 "B.SilkS" user "Ref Des/Silkscreen Bottom")
		(1 "F.Mask" user "Board Geometry/Soldermask Top")
		(3 "B.Mask" user "Board Geometry/Soldermask Bottom")
		(17 "Dwgs.User" user "User.Drawings")
		(19 "Cmts.User" user "User.Comments")
		(21 "Eco1.User" user "User.Eco1")
		(23 "Eco2.User" user "User.Eco2")
		(25 "Edge.Cuts" user "Board Geometry/Outline")
		(27 "Margin" user)
		(31 "F.CrtYd" user "Package Geometry/Place Bound Top")
		(29 "B.CrtYd" user "Package Geometry/Place Bound Bottom")
		(35 "F.Fab" user "Ref Des/Assembly Top")
		(33 "B.Fab" user "Ref Des/Assembly Bottom")
	)
	(footprint ""
		(layer "B.Cu")
		(at 58.8264 -77.401928 -90)
		(property "Reference" "C102"
			(at 32.15894 14.43355 270)
			(unlocked yes)
			(layer "B.SilkS")
			(effects
				(font
					(size 0.7874 0.5842)
					(thickness 0.1524)
				)
				(justify left mirror)
			)
		)
		(property "Value" ""
			(at 0 0 90)
			(layer "B.Fab")
			(effects
				(font
					(size 1.27 1.27)
				)
				(justify mirror)
			)
		)
		(duplicate_pad_numbers_are_jumpers no)
		(fp_line
			(start -0.7874 0.4064)
			(end 0.7874 0.4064)
			(stroke
				(width 0.1524)
				(type default)
			)
			(layer "B.SilkS")
		)
		(fp_line
			(start 0.7874 0.4064)
			(end 0.7874 -0.4064)
			(stroke
				(width 0.1524)
				(type default)
			)
			(layer "B.SilkS")
		)
		(fp_line
			(start 0 0.381)
			(end 0 -0.381)
			(stroke
				(width 0.1524)
				(type default)
			)
			(layer "B.SilkS")
		)
		(fp_line
			(start -0.7874 -0.4064)
			(end -0.7874 0.4064)
			(stroke
				(width 0.1524)
				(type default)
			)
			(layer "B.SilkS")
		)
		(fp_line
			(start 0.7874 -0.4064)
			(end -0.7874 -0.4064)
			(stroke
				(width 0.1524)
				(type default)
			)
			(layer "B.SilkS")
		)
		(fp_poly
			(pts
				(xy 0.5334 0.254) (xy 0.635 0.254) (xy 0.635 0.2286) (xy 0.635 -0.254) (xy 0.5334 -0.254) (xy 0.5334 -0.2794)
				(xy -0.5334 -0.2794) (xy -0.5334 -0.254) (xy -0.635 -0.254) (xy -0.635 0.254) (xy -0.5334 0.254)
				(xy -0.5334 0.2794) (xy 0.508 0.2794) (xy 0.5334 0.2794)
			)
			(stroke
				(width 0)
				(type default)
			)
			(fill no)
			(layer "B.CrtYd")
		)
		(pad "1" smd rect
			(at -0.40005 0 90)
			(size 0.4572 0.508)
			(layers "B.Cu" "B.Mask" "B.Paste")
			(net "P1V05_NODE1")
		)
		(pad "2" smd rect
			(at 0.40005 0 90)
			(size 0.4572 0.508)
			(layers "B.Cu" "B.Mask" "B.Paste")
			(net "GND")
		)
	)
	(footprint ""
		(layer "B.Cu")
		(at 121.72061 -36.414456 180)
		(property "Reference" "R1202"
			(at 3.310636 -0.941578 0)
			(unlocked yes)
			(layer "B.SilkS")
			(effects
				(font
					(size 0.7874 0.5842)
					(thickness 0.1524)
				)
				(justify left mirror)
			)
		)
		(property "Value" ""
			(at 0 0 0)
			(layer "B.Fab")
			(effects
				(font
					(size 1.27 1.27)
				)
				(justify mirror)
			)
		)
		(duplicate_pad_numbers_are_jumpers no)
		(fp_line
			(start 0.7874 0.4064)
			(end 0.7874 -0.4064)
			(stroke
				(width 0.1524)
				(type default)
			)
			(layer "B.SilkS")
		)
		(fp_line
			(start 0.7874 -0.4064)
			(end -0.7874 -0.4064)
			(stroke
				(width 0.1524)
				(type default)
			)
			(layer "B.SilkS")
		)
		(fp_line
			(start -0.7874 0.4064)
			(end 0.7874 0.4064)
			(stroke
				(width 0.1524)
				(type default)
			)
			(layer "B.SilkS")
		)
		(fp_line
			(start -0.7874 -0.4064)
			(end -0.7874 0.4064)
			(stroke
				(width 0.1524)
				(type default)
			)
			(layer "B.SilkS")
		)
		(fp_poly
			(pts
				(xy 0.508 0.2794) (xy 0.508 0.2286) (xy 0.635 0.2286) (xy 0.635 -0.254) (xy 0.5334 -0.254) (xy 0.5334 -0.2794)
				(xy -0.5334 -0.2794) (xy -0.5334 -0.254) (xy -0.635 -0.254) (xy -0.635 0.254) (xy -0.5334 0.254)
				(xy -0.5334 0.2794)
			)
			(stroke
				(width 0)
				(type default)
			)
			(fill no)
			(layer "B.CrtYd")
		)
		(pad "1" smd rect
			(at -0.40005 0)
			(size 0.4572 0.508)
			(layers "B.Cu" "B.Mask" "B.Paste")
			(net "SIO_JTAG_CPLD3_TDI_R")
		)
		(pad "2" smd rect
			(at 0.40005 0)
			(size 0.4572 0.508)
			(layers "B.Cu" "B.Mask" "B.Paste")
			(net "P3V3_NODE1")
		)
	)
	(footprint ""
		(layer "B.Cu")
		(at 70.346062 -29.394658 90)
		(property "Reference" "R202"
			(at 1.302766 -0.213106 270)
			(unlocked yes)
			(layer "B.SilkS")
			(effects
				(font
					(size 0.7874 0.5842)
					(thickness 0.1524)
				)
				(justify left mirror)
			)
		)
		(property "Value" ""
			(at 0 0 90)
			(layer "B.Fab")
			(effects
				(font
					(size 1.27 1.27)
				)
				(justify mirror)
			)
		)
		(duplicate_pad_numbers_are_jumpers no)
		(fp_line
			(start 0.7874 -0.4064)
			(end -0.7874 -0.4064)
			(stroke
				(width 0.1524)
				(type default)
			)
			(layer "B.SilkS")
		)
		(fp_line
			(start -0.7874 -0.4064)
			(end -0.7874 0.4064)
			(stroke
				(width 0.1524)
				(type default)
			)
			(layer "B.SilkS")
		)
		(fp_line
			(start 0.7874 0.4064)
			(end 0.7874 -0.4064)
			(stroke
				(width 0.1524)
				(type default)
			)
			(layer "B.SilkS")
		)
		(fp_line
			(start -0.7874 0.4064)
			(end 0.7874 0.4064)
			(stroke
				(width 0.1524)
				(type default)
			)
			(layer "B.SilkS")
		)
		(fp_poly
			(pts
				(xy 0.508 0.2794) (xy 0.508 0.2286) (xy 0.635 0.2286) (xy 0.635 -0.254) (xy 0.5334 -0.254) (xy 0.5334 -0.2794)
				(xy -0.5334 -0.2794) (xy -0.5334 -0.254) (xy -0.635 -0.254) (xy -0.635 0.254) (xy -0.5334 0.254)
				(xy -0.5334 0.2794)
			)
			(stroke
				(width 0)
				(type default)
			)
			(fill no)
			(layer "B.CrtYd")
		)
		(pad "1" smd rect
			(at -0.40005 0 270)
			(size 0.4572 0.508)
			(layers "B.Cu" "B.Mask" "B.Paste")
			(net "PV_VDDR_NODE1")
		)
		(pad "2" smd rect
			(at 0.40005 0 270)
			(size 0.4572 0.508)
			(layers "B.Cu" "B.Mask" "B.Paste")
			(net "P1V5_NODE1_DDR3_VREF_A_A")
		)
	)
	(footprint ""
		(layer "B.Cu")
		(at 65.786 -131.554474 90)
		(property "Reference" "C254"
			(at -54.867048 -41.245282 270)
			(unlocked yes)
			(layer "B.SilkS")
			(effects
				(font
					(size 0.7874 0.5842)
					(thickness 0.1524)
				)
				(justify left mirror)
			)
		)
		(property "Value" ""
			(at 0 0 90)
			(layer "B.Fab")
			(effects
				(font
					(size 1.27 1.27)
				)
				(justify mirror)
			)
		)
		(duplicate_pad_numbers_are_jumpers no)
		(fp_line
			(start 0.7874 -0.4064)
			(end -0.7874 -0.4064)
			(stroke
				(width 0.1524)
				(type default)
			)
			(layer "B.SilkS")
		)
		(fp_line
			(start -0.7874 -0.4064)
			(end -0.7874 0.4064)
			(stroke
				(width 0.1524)
				(type default)
			)
			(layer "B.SilkS")
		)
		(fp_line
			(start 0 0.381)
			(end 0 -0.381)
			(stroke
				(width 0.1524)
				(type default)
			)
			(layer "B.SilkS")
		)
		(fp_line
			(start 0.7874 0.4064)
			(end 0.7874 -0.4064)
			(stroke
				(width 0.1524)
				(type default)
			)
			(layer "B.SilkS")
		)
		(fp_line
			(start -0.7874 0.4064)
			(end 0.7874 0.4064)
			(stroke
				(width 0.1524)
				(type default)
			)
			(layer "B.SilkS")
		)
		(fp_poly
			(pts
				(xy 0.5334 0.254) (xy 0.635 0.254) (xy 0.635 0.2286) (xy 0.635 -0.254) (xy 0.5334 -0.254) (xy 0.5334 -0.2794)
				(xy -0.5334 -0.2794) (xy -0.5334 -0.254) (xy -0.635 -0.254) (xy -0.635 0.254) (xy -0.5334 0.254)
				(xy -0.5334 0.2794) (xy 0.508 0.2794) (xy 0.5334 0.2794)
			)
			(stroke
				(width 0)
				(type default)
			)
			(fill no)
			(layer "B.CrtYd")
		)
		(pad "1" smd rect
			(at -0.40005 0 270)
			(size 0.4572 0.508)
			(layers "B.Cu" "B.Mask" "B.Paste")
			(net "P3V3_NODE1")
		)
		(pad "2" smd rect
			(at 0.40005 0 270)
			(size 0.4572 0.508)
			(layers "B.Cu" "B.Mask" "B.Paste")
			(net "GND")
		)
	)
	(footprint ""
		(layer "B.Cu")
		(at 53.199538 -74.959718 90)
		(property "Reference" "C50"
			(at -32.304228 -14.331188 270)
			(unlocked yes)
			(layer "B.SilkS")
			(effects
				(font
					(size 0.7874 0.5842)
					(thickness 0.1524)
				)
				(justify left mirror)
			)
		)
		(property "Value" ""
			(at 0 0 90)
			(layer "B.Fab")
			(effects
				(font
					(size 1.27 1.27)
				)
				(justify mirror)
			)
		)
		(duplicate_pad_numbers_are_jumpers no)
		(fp_line
			(start 0.7874 -0.4064)
			(end -0.7874 -0.4064)
			(stroke
				(width 0.1524)
				(type default)
			)
			(layer "B.SilkS")
		)
		(fp_line
			(start -0.7874 -0.4064)
			(end -0.7874 0.4064)
			(stroke
				(width 0.1524)
				(type default)
			)
			(layer "B.SilkS")
		)
		(fp_line
			(start 0 0.381)
			(end 0 -0.381)
			(stroke
				(width 0.1524)
				(type default)
			)
			(layer "B.SilkS")
		)
		(fp_line
			(start 0.7874 0.4064)
			(end 0.7874 -0.4064)
			(stroke
				(width 0.1524)
				(type default)
			)
			(layer "B.SilkS")
		)
		(fp_line
			(start -0.7874 0.4064)
			(end 0.7874 0.4064)
			(stroke
				(width 0.1524)
				(type default)
			)
			(layer "B.SilkS")
		)
		(fp_poly
			(pts
				(xy 0.5334 0.254) (xy 0.635 0.254) (xy 0.635 0.2286) (xy 0.635 -0.254) (xy 0.5334 -0.254) (xy 0.5334 -0.2794)
				(xy -0.5334 -0.2794) (xy -0.5334 -0.254) (xy -0.635 -0.254) (xy -0.635 0.254) (xy -0.5334 0.254)
				(xy -0.5334 0.2794) (xy 0.508 0.2794) (xy 0.5334 0.2794)
			)
			(stroke
				(width 0)
				(type default)
			)
			(fill no)
			(layer "B.CrtYd")
		)
		(pad "1" smd rect
			(at -0.40005 0 270)
			(size 0.4572 0.508)
			(layers "B.Cu" "B.Mask" "B.Paste")
			(net "P1V05_NODE1")
		)
		(pad "2" smd rect
			(at 0.40005 0 270)
			(size 0.4572 0.508)
			(layers "B.Cu" "B.Mask" "B.Paste")
			(net "GND")
		)
	)
	(footprint ""
		(layer "B.Cu")
		(at 154.06116 -172.505624)
		(property "Reference" "R749"
			(at -1.545844 12.970002 0)
			(unlocked yes)
			(layer "B.SilkS")
			(effects
				(font
					(size 0.7874 0.5842)
					(thickness 0.1524)
				)
				(justify left mirror)
			)
		)
		(property "Value" ""
			(at 0 0 0)
			(layer "B.Fab")
			(effects
				(font
					(size 1.27 1.27)
				)
				(justify mirror)
			)
		)
		(duplicate_pad_numbers_are_jumpers no)
		(fp_line
			(start -0.7874 -0.4064)
			(end -0.7874 0.4064)
			(stroke
				(width 0.1524)
				(type default)
			)
			(layer "B.SilkS")
		)
		(fp_line
			(start -0.7874 0.4064)
			(end 0.7874 0.4064)
			(stroke
				(width 0.1524)
				(type default)
			)
			(layer "B.SilkS")
		)
		(fp_line
			(start 0.7874 -0.4064)
			(end -0.7874 -0.4064)
			(stroke
				(width 0.1524)
				(type default)
			)
			(layer "B.SilkS")
		)
		(fp_line
			(start 0.7874 0.4064)
			(end 0.7874 -0.4064)
			(stroke
				(width 0.1524)
				(type default)
			)
			(layer "B.SilkS")
		)
		(fp_poly
			(pts
				(xy 0.508 0.2794) (xy 0.508 0.2286) (xy 0.635 0.2286) (xy 0.635 -0.254) (xy 0.5334 -0.254) (xy 0.5334 -0.2794)
				(xy -0.5334 -0.2794) (xy -0.5334 -0.254) (xy -0.635 -0.254) (xy -0.635 0.254) (xy -0.5334 0.254)
				(xy -0.5334 0.2794)
			)
			(stroke
				(width 0)
				(type default)
			)
			(fill no)
			(layer "B.CrtYd")
		)
		(pad "1" smd rect
			(at -0.40005 0 180)
			(size 0.4572 0.508)
			(layers "B.Cu" "B.Mask" "B.Paste")
			(net "T12_NODE4_EN")
		)
		(pad "2" smd rect
			(at 0.40005 0 180)
			(size 0.4572 0.508)
			(layers "B.Cu" "B.Mask" "B.Paste")
			(net "P5V_NODE1")
		)
	)
	(footprint ""
		(layer "B.Cu")
		(at 75.269852 -139.385802)
		(property "Reference" "TP5"
			(at 0 0 0)
			(layer "B.SilkS")
			(hide yes)
			(effects
				(font
					(size 1.27 1.27)
				)
				(justify mirror)
			)
		)
		(property "Value" ""
			(at 0 0 0)
			(layer "B.Fab")
			(effects
				(font
					(size 1.27 1.27)
				)
				(justify mirror)
			)
		)
		(duplicate_pad_numbers_are_jumpers no)
		(fp_poly
			(pts
				(arc
					(start 0 -0.381)
					(mid 0 0.381)
					(end 0 -0.381)
				)
			)
			(stroke
				(width 0)
				(type default)
			)
			(fill no)
			(layer "B.CrtYd")
		)
		(pad "1" smd circle
			(at 0 0 180)
			(size 0.762 0.762)
			(layers "B.Cu" "B.Mask" "B.Paste")
			(net "N3975090765")
		)
	)
	(footprint ""
		(layer "B.Cu")
		(at 120.370092 -165.410642 -90)
		(property "Reference" "R1225"
			(at 2.96418 -2.73431 270)
			(unlocked yes)
			(layer "B.SilkS")
			(effects
				(font
					(size 0.7874 0.5842)
					(thickness 0.1524)
				)
				(justify left mirror)
			)
		)
		(property "Value" ""
			(at 0 0 90)
			(layer "B.Fab")
			(effects
				(font
					(size 1.27 1.27)
				)
				(justify mirror)
			)
		)
		(duplicate_pad_numbers_are_jumpers no)
		(fp_line
			(start -0.7874 0.4064)
			(end 0.7874 0.4064)
			(stroke
				(width 0.1524)
				(type default)
			)
			(layer "B.SilkS")
		)
		(fp_line
			(start 0.7874 0.4064)
			(end 0.7874 -0.4064)
			(stroke
				(width 0.1524)
				(type default)
			)
			(layer "B.SilkS")
		)
		(fp_line
			(start -0.7874 -0.4064)
			(end -0.7874 0.4064)
			(stroke
				(width 0.1524)
				(type default)
			)
			(layer "B.SilkS")
		)
		(fp_line
			(start 0.7874 -0.4064)
			(end -0.7874 -0.4064)
			(stroke
				(width 0.1524)
				(type default)
			)
			(layer "B.SilkS")
		)
		(fp_poly
			(pts
				(xy 0.508 0.2794) (xy 0.508 0.2286) (xy 0.635 0.2286) (xy 0.635 -0.254) (xy 0.5334 -0.254) (xy 0.5334 -0.2794)
				(xy -0.5334 -0.2794) (xy -0.5334 -0.254) (xy -0.635 -0.254) (xy -0.635 0.254) (xy -0.5334 0.254)
				(xy -0.5334 0.2794)
			)
			(stroke
				(width 0)
				(type default)
			)
			(fill no)
			(layer "B.CrtYd")
		)
		(pad "1" smd rect
			(at -0.40005 0 90)
			(size 0.4572 0.508)
			(layers "B.Cu" "B.Mask" "B.Paste")
			(net "FAN_MAX_CTRL")
		)
		(pad "2" smd rect
			(at 0.40005 0 90)
			(size 0.4572 0.508)
			(layers "B.Cu" "B.Mask" "B.Paste")
			(net "GND")
		)
	)
	(footprint ""
		(layer "B.Cu")
		(at 63.10376 -188.126624 -90)
		(property "Reference" "C631"
			(at -4.276598 0.212598 270)
			(unlocked yes)
			(layer "B.SilkS")
			(effects
				(font
					(size 0.7874 0.5842)
					(thickness 0.1524)
				)
				(justify left mirror)
			)
		)
		(property "Value" ""
			(at 0 0 90)
			(layer "B.Fab")
			(effects
				(font
					(size 1.27 1.27)
				)
				(justify mirror)
			)
		)
		(duplicate_pad_numbers_are_jumpers no)
		(fp_line
			(start -0.7874 0.4064)
			(end 0.7874 0.4064)
			(stroke
				(width 0.1524)
				(type default)
			)
			(layer "B.SilkS")
		)
		(fp_line
			(start 0.7874 0.4064)
			(end 0.7874 -0.4064)
			(stroke
				(width 0.1524)
				(type default)
			)
			(layer "B.SilkS")
		)
		(fp_line
			(start 0 0.381)
			(end 0 -0.381)
			(stroke
				(width 0.1524)
				(type default)
			)
			(layer "B.SilkS")
		)
		(fp_line
			(start -0.7874 -0.4064)
			(end -0.7874 0.4064)
			(stroke
				(width 0.1524)
				(type default)
			)
			(layer "B.SilkS")
		)
		(fp_line
			(start 0.7874 -0.4064)
			(end -0.7874 -0.4064)
			(stroke
				(width 0.1524)
				(type default)
			)
			(layer "B.SilkS")
		)
		(fp_poly
			(pts
				(xy 0.5334 0.254) (xy 0.635 0.254) (xy 0.635 0.2286) (xy 0.635 -0.254) (xy 0.5334 -0.254) (xy 0.5334 -0.2794)
				(xy -0.5334 -0.2794) (xy -0.5334 -0.254) (xy -0.635 -0.254) (xy -0.635 0.254) (xy -0.5334 0.254)
				(xy -0.5334 0.2794) (xy 0.508 0.2794) (xy 0.5334 0.2794)
			)
			(stroke
				(width 0)
				(type default)
			)
			(fill no)
			(layer "B.CrtYd")
		)
		(pad "1" smd rect
			(at -0.40005 0 90)
			(size 0.4572 0.508)
			(layers "B.Cu" "B.Mask" "B.Paste")
			(net "T1_NODE4_EN_R")
		)
		(pad "2" smd rect
			(at 0.40005 0 90)
			(size 0.4572 0.508)
			(layers "B.Cu" "B.Mask" "B.Paste")
			(net "GND")
		)
	)
	(footprint ""
		(layer "B.Cu")
		(at 48.274732 -88.473026 90)
		(property "Reference" "R97"
			(at 0.913892 -0.1397 270)
			(unlocked yes)
			(layer "B.SilkS")
			(effects
				(font
					(size 0.7874 0.5842)
					(thickness 0.1524)
				)
				(justify left mirror)
			)
		)
		(property "Value" ""
			(at 0 0 90)
			(layer "B.Fab")
			(effects
				(font
					(size 1.27 1.27)
				)
				(justify mirror)
			)
		)
		(duplicate_pad_numbers_are_jumpers no)
		(fp_line
			(start 0.7874 -0.4064)
			(end -0.7874 -0.4064)
			(stroke
				(width 0.1524)
				(type default)
			)
			(layer "B.SilkS")
		)
		(fp_line
			(start -0.7874 -0.4064)
			(end -0.7874 0.4064)
			(stroke
				(width 0.1524)
				(type default)
			)
			(layer "B.SilkS")
		)
		(fp_line
			(start 0.7874 0.4064)
			(end 0.7874 -0.4064)
			(stroke
				(width 0.1524)
				(type default)
			)
			(layer "B.SilkS")
		)
		(fp_line
			(start -0.7874 0.4064)
			(end 0.7874 0.4064)
			(stroke
				(width 0.1524)
				(type default)
			)
			(layer "B.SilkS")
		)
		(fp_poly
			(pts
				(xy 0.508 0.2794) (xy 0.508 0.2286) (xy 0.635 0.2286) (xy 0.635 -0.254) (xy 0.5334 -0.254) (xy 0.5334 -0.2794)
				(xy -0.5334 -0.2794) (xy -0.5334 -0.254) (xy -0.635 -0.254) (xy -0.635 0.254) (xy -0.5334 0.254)
				(xy -0.5334 0.2794)
			)
			(stroke
				(width 0)
				(type default)
			)
			(fill no)
			(layer "B.CrtYd")
		)
		(pad "1" smd rect
			(at -0.40005 0 270)
			(size 0.4572 0.508)
			(layers "B.Cu" "B.Mask" "B.Paste")
			(net "PD_NODE1_NTB_CLKINP")
		)
		(pad "2" smd rect
			(at 0.40005 0 270)
			(size 0.4572 0.508)
			(layers "B.Cu" "B.Mask" "B.Paste")
			(net "GND")
		)
	)
)
